# S9S_MB_2U (Grand Teton) — schematic netlist excerpt (pin names and nets, part order shuffled) for the footprints in the layout excerpt that follows; sources: Cadence DE-HDL packaged netlist, KiCad conversion of 03242023_DA0F0TMBIJ0_F0T_Motherboard_J_brd_V01_OCP.brd

PC1239  Q_CAP  22UF 4V 20% X6S  pkg C0805  page 263 : A = P1V8_PCH_AUX ; B = GND
C312  Q_CAP  47UF 4V 20% X6S  pkg C0805  page 78 : A = PVCCIN_CPU1 ; B = GND
PC2340  Q_CAP  560PF 50V 10% X7R  pkg C0402  page 242 : A = P12V_SCM_ISET_R ; B = GND

(kicad_pcb
	(version 20260206)
	(generator "pcbnew")
	(generator_version "10.0")
	(general
		(thickness 1.6)
		(legacy_teardrops no)
	)
	(paper "A4")
	(title_block
		(title "03242023_DA0F0TMBIJ0_F0T_Motherboard_J_brd_V01_OCP.brd")
		(comment 1 "Grand Teton / footprints 5951-5953 of 6105")
	)
	(layers
		(0 "F.Cu" signal "TOP")
		(4 "In1.Cu" signal "GND")
		(6 "In2.Cu" signal "IN1")
		(8 "In3.Cu" signal "GND1")
		(10 "In4.Cu" signal "IN2")
		(12 "In5.Cu" signal "GND2")
		(14 "In6.Cu" signal "IN3")
		(16 "In7.Cu" signal "GND3")
		(18 "In8.Cu" signal "VCC")
		(20 "In9.Cu" signal "VCC1")
		(22 "In10.Cu" signal "GND4")
		(24 "In11.Cu" signal "IN4")
		(26 "In12.Cu" signal "GND5")
		(28 "In13.Cu" signal "IN5")
		(30 "In14.Cu" signal "GND6")
		(32 "In15.Cu" signal "IN6")
		(34 "In16.Cu" signal "GND7")
		(2 "B.Cu" signal "BOTTOM")
		(9 "F.Adhes" user "F.Adhesive")
		(11 "B.Adhes" user "B.Adhesive")
		(13 "F.Paste" user "Package Geometry/Pastemask Top")
		(15 "B.Paste" user "Package Geometry/Pastemask Bottom")
		(5 "F.SilkS" user "Ref Des/Silkscreen Top")
		(7 "B.SilkS" user "Ref Des/Silkscreen Bottom")
		(1 "F.Mask" user "Board Geometry/Soldermask Top")
		(3 "B.Mask" user "Board Geometry/Soldermask Bottom")
		(17 "Dwgs.User" user "User.Drawings")
		(19 "Cmts.User" user "User.Comments")
		(21 "Eco1.User" user "User.Eco1")
		(23 "Eco2.User" user "User.Eco2")
		(25 "Edge.Cuts" user "Board Geometry/Outline")
		(27 "Margin" user)
		(31 "F.CrtYd" user "Package Geometry/Place Bound Top")
		(29 "B.CrtYd" user "Package Geometry/Place Bound Bottom")
		(35 "F.Fab" user "Ref Des/Assembly Top")
		(33 "B.Fab" user "Ref Des/Assembly Bottom")
	)
	(footprint ""
		(layer "B.Cu")
		(at 376.468132 -76.696824 180)
		(property "Reference" "PC1239"
			(at 0 0 0)
			(layer "B.SilkS")
			(hide yes)
			(effects
				(font
					(size 1.27 1.27)
				)
				(justify mirror)
			)
		)
		(property "Value" ""
			(at 0 0 0)
			(layer "B.Fab")
			(effects
				(font
					(size 1.27 1.27)
				)
				(justify mirror)
			)
		)
		(duplicate_pad_numbers_are_jumpers no)
		(fp_line
			(start 1.524 0.762)
			(end 1.524 -0.762)
			(stroke
				(width 0.1524)
				(type default)
			)
			(layer "B.SilkS")
		)
		(fp_line
			(start 1.524 -0.762)
			(end -1.524 -0.762)
			(stroke
				(width 0.1524)
				(type default)
			)
			(layer "B.SilkS")
		)
		(fp_line
			(start -1.524 0.762)
			(end 1.524 0.762)
			(stroke
				(width 0.1524)
				(type default)
			)
			(layer "B.SilkS")
		)
		(fp_line
			(start -1.524 -0.762)
			(end -1.524 0.762)
			(stroke
				(width 0.1524)
				(type default)
			)
			(layer "B.SilkS")
		)
		(fp_line
			(start 1.1049 0.724916)
			(end -1.1049 0.724916)
			(stroke
				(width 0.1)
				(type default)
			)
			(layer "B.Fab")
		)
		(fp_line
			(start 1.1049 -0.724916)
			(end 1.1049 0.724916)
			(stroke
				(width 0.1)
				(type default)
			)
			(layer "B.Fab")
		)
		(fp_line
			(start -1.1049 0.724916)
			(end -1.1049 -0.724916)
			(stroke
				(width 0.1)
				(type default)
			)
			(layer "B.Fab")
		)
		(fp_line
			(start -1.1049 -0.724916)
			(end 1.1049 -0.724916)
			(stroke
				(width 0.1)
				(type default)
			)
			(layer "B.Fab")
		)
		(pad "1" smd rect
			(at 0.889 0 180)
			(size 1.016 1.27)
			(layers "B.Cu" "B.Mask" "B.Paste")
			(net "P1V8_PCH_AUX")
		)
		(pad "2" smd rect
			(at -0.889 0 180)
			(size 1.016 1.27)
			(layers "B.Cu" "B.Mask" "B.Paste")
			(net "GND")
		)
	)
	(footprint ""
		(layer "B.Cu")
		(at 178.04384 -32.944308 90)
		(property "Reference" "PC2340"
			(at 0 0 90)
			(layer "B.SilkS")
			(hide yes)
			(effects
				(font
					(size 1.27 1.27)
				)
				(justify mirror)
			)
		)
		(property "Value" ""
			(at 0 0 90)
			(layer "B.Fab")
			(effects
				(font
					(size 1.27 1.27)
				)
				(justify mirror)
			)
		)
		(duplicate_pad_numbers_are_jumpers no)
		(fp_line
			(start 0.7874 -0.4064)
			(end -0.7874 -0.4064)
			(stroke
				(width 0.1524)
				(type default)
			)
			(layer "B.SilkS")
		)
		(fp_line
			(start -0.7874 -0.4064)
			(end -0.7874 0.4064)
			(stroke
				(width 0.1524)
				(type default)
			)
			(layer "B.SilkS")
		)
		(fp_line
			(start 0.7874 0.4064)
			(end 0.7874 -0.4064)
			(stroke
				(width 0.1524)
				(type default)
			)
			(layer "B.SilkS")
		)
		(fp_line
			(start -0.7874 0.4064)
			(end 0.7874 0.4064)
			(stroke
				(width 0.1524)
				(type default)
			)
			(layer "B.SilkS")
		)
		(fp_line
			(start 0.67945 -0.305054)
			(end 0.12065 -0.305054)
			(stroke
				(width 0.1)
				(type default)
			)
			(layer "B.Fab")
		)
		(fp_line
			(start 0.12065 -0.305054)
			(end 0.12065 -0.2794)
			(stroke
				(width 0.1)
				(type default)
			)
			(layer "B.Fab")
		)
		(fp_line
			(start -0.12065 -0.3048)
			(end -0.67945 -0.3048)
			(stroke
				(width 0.1)
				(type default)
			)
			(layer "B.Fab")
		)
		(fp_line
			(start -0.67945 -0.3048)
			(end -0.67945 0.3048)
			(stroke
				(width 0.1)
				(type default)
			)
			(layer "B.Fab")
		)
		(fp_line
			(start 0.12065 -0.2794)
			(end -0.12065 -0.2794)
			(stroke
				(width 0.1)
				(type default)
			)
			(layer "B.Fab")
		)
		(fp_line
			(start -0.12065 -0.2794)
			(end -0.12065 -0.3048)
			(stroke
				(width 0.1)
				(type default)
			)
			(layer "B.Fab")
		)
		(fp_line
			(start 0.12065 0.2794)
			(end 0.12065 0.3048)
			(stroke
				(width 0.1)
				(type default)
			)
			(layer "B.Fab")
		)
		(fp_line
			(start -0.120396 0.2794)
			(end 0.12065 0.2794)
			(stroke
				(width 0.1)
				(type default)
			)
			(layer "B.Fab")
		)
		(fp_line
			(start 0.67945 0.3048)
			(end 0.67945 -0.305054)
			(stroke
				(width 0.1)
				(type default)
			)
			(layer "B.Fab")
		)
		(fp_line
			(start 0.12065 0.3048)
			(end 0.67945 0.3048)
			(stroke
				(width 0.1)
				(type default)
			)
			(layer "B.Fab")
		)
		(fp_line
			(start -0.120396 0.3048)
			(end -0.120396 0.2794)
			(stroke
				(width 0.1)
				(type default)
			)
			(layer "B.Fab")
		)
		(fp_line
			(start -0.67945 0.3048)
			(end -0.120396 0.3048)
			(stroke
				(width 0.1)
				(type default)
			)
			(layer "B.Fab")
		)
		(pad "1" smd circle
			(at 0.40005 0 270)
			(size 0 0)
			(layers "B.Cu" "B.Mask" "B.Paste")
			(net "P12V_SCM_ISET_R")
		)
		(pad "2" smd circle
			(at -0.40005 0 270)
			(size 0 0)
			(layers "B.Cu" "B.Mask" "B.Paste")
			(net "GND")
		)
	)
	(footprint ""
		(layer "B.Cu")
		(at 105.595928 -262.34898)
		(property "Reference" "C312"
			(at 0 0 0)
			(layer "B.SilkS")
			(hide yes)
			(effects
				(font
					(size 1.27 1.27)
				)
				(justify mirror)
			)
		)
		(property "Value" ""
			(at 0 0 0)
			(layer "B.Fab")
			(effects
				(font
					(size 1.27 1.27)
				)
				(justify mirror)
			)
		)
		(duplicate_pad_numbers_are_jumpers no)
		(fp_line
			(start -1.524 -0.762)
			(end -1.524 0.762)
			(stroke
				(width 0.1524)
				(type default)
			)
			(layer "B.SilkS")
		)
		(fp_line
			(start -1.524 0.762)
			(end 1.524 0.762)
			(stroke
				(width 0.1524)
				(type default)
			)
			(layer "B.SilkS")
		)
		(fp_line
			(start 1.524 -0.762)
			(end -1.524 -0.762)
			(stroke
				(width 0.1524)
				(type default)
			)
			(layer "B.SilkS")
		)
		(fp_line
			(start 1.524 0.762)
			(end 1.524 -0.762)
			(stroke
				(width 0.1524)
				(type default)
			)
			(layer "B.SilkS")
		)
		(fp_line
			(start -1.1049 -0.724916)
			(end 1.1049 -0.724916)
			(stroke
				(width 0.1)
				(type default)
			)
			(layer "B.Fab")
		)
		(fp_line
			(start -1.1049 0.724916)
			(end -1.1049 -0.724916)
			(stroke
				(width 0.1)
				(type default)
			)
			(layer "B.Fab")
		)
		(fp_line
			(start 1.1049 -0.724916)
			(end 1.1049 0.724916)
			(stroke
				(width 0.1)
				(type default)
			)
			(layer "B.Fab")
		)
		(fp_line
			(start 1.1049 0.724916)
			(end -1.1049 0.724916)
			(stroke
				(width 0.1)
				(type default)
			)
			(layer "B.Fab")
		)
		(pad "1" smd rect
			(at 0.889 0)
			(size 1.016 1.27)
			(layers "B.Cu" "B.Mask" "B.Paste")
			(net "PVCCIN_CPU1")
		)
		(pad "2" smd rect
			(at -0.889 0)
			(size 1.016 1.27)
			(layers "B.Cu" "B.Mask" "B.Paste")
			(net "GND")
		)
	)
)
